# T6G (Grand Teton) — schematic netlist excerpt (pin names and nets, part order shuffled) for the footprints in the layout excerpt that follows; sources: Cadence DE-HDL packaged netlist, KiCad conversion of 04192023_DAF0TMB3IC0_F0TG_MB_C_brd_V02_OCP.brd

R3272  Q_RES  1K 1% EMPTY  pkg 0402LF  page 111 : A = FM_P2E_EQA1 ; B = GND
C19  Q_CAP  0.1UF 25V 10% X7R  pkg 0402  page 125 : A = PRSNT_CABLE_GPU_A2_ISO_N ; B = GND

(kicad_pcb
	(version 20260206)
	(generator "pcbnew")
	(generator_version "10.0")
	(general
		(thickness 1.6)
		(legacy_teardrops no)
	)
	(paper "A4")
	(title_block
		(title "04192023_DAF0TMB3IC0_F0TG_MB_C_brd_V02_OCP.brd")
		(comment 1 "Grand Teton / footprints 2907-2908 of 8354")
	)
	(layers
		(0 "F.Cu" signal "TOP")
		(4 "In1.Cu" signal "GND")
		(6 "In2.Cu" signal "IN1")
		(8 "In3.Cu" signal "GND1")
		(10 "In4.Cu" signal "IN2")
		(12 "In5.Cu" signal "GND2")
		(14 "In6.Cu" signal "IN3")
		(16 "In7.Cu" signal "GND3")
		(18 "In8.Cu" signal "VCC")
		(20 "In9.Cu" signal "VCC1")
		(22 "In10.Cu" signal "GND4")
		(24 "In11.Cu" signal "IN4")
		(26 "In12.Cu" signal "GND5")
		(28 "In13.Cu" signal "IN5")
		(30 "In14.Cu" signal "GND6")
		(32 "In15.Cu" signal "IN6")
		(34 "In16.Cu" signal "GND7")
		(2 "B.Cu" signal "BOTTOM")
		(9 "F.Adhes" user "F.Adhesive")
		(11 "B.Adhes" user "B.Adhesive")
		(13 "F.Paste" user "Package Geometry/Pastemask Top")
		(15 "B.Paste" user "Package Geometry/Pastemask Bottom")
		(5 "F.SilkS" user "Ref Des/Silkscreen Top")
		(7 "B.SilkS" user "Ref Des/Silkscreen Bottom")
		(1 "F.Mask" user "Board Geometry/Soldermask Top")
		(3 "B.Mask" user "Board Geometry/Soldermask Bottom")
		(17 "Dwgs.User" user "User.Drawings")
		(19 "Cmts.User" user "User.Comments")
		(21 "Eco1.User" user "User.Eco1")
		(23 "Eco2.User" user "User.Eco2")
		(25 "Edge.Cuts" user "Board Geometry/Outline")
		(27 "Margin" user)
		(31 "F.CrtYd" user "Package Geometry/Place Bound Top")
		(29 "B.CrtYd" user "Package Geometry/Place Bound Bottom")
		(35 "F.Fab" user "Ref Des/Assembly Top")
		(33 "B.Fab" user "Ref Des/Assembly Bottom")
	)
	(footprint ""
		(layer "F.Cu")
		(at 30.569662 -419.249098 -90)
		(property "Reference" "R3272"
			(at 0 0 270)
			(layer "F.SilkS")
			(hide yes)
			(effects
				(font
					(size 1.27 1.27)
				)
			)
		)
		(property "Value" ""
			(at 0 0 270)
			(layer "F.Fab")
			(effects
				(font
					(size 1.27 1.27)
				)
			)
		)
		(duplicate_pad_numbers_are_jumpers no)
		(fp_line
			(start -0.7874 0.4064)
			(end -0.7874 -0.4064)
			(stroke
				(width 0.1524)
				(type default)
			)
			(layer "F.SilkS")
		)
		(fp_line
			(start 0.7874 0.4064)
			(end -0.7874 0.4064)
			(stroke
				(width 0.1524)
				(type default)
			)
			(layer "F.SilkS")
		)
		(fp_line
			(start -0.7874 -0.4064)
			(end 0.7874 -0.4064)
			(stroke
				(width 0.1524)
				(type default)
			)
			(layer "F.SilkS")
		)
		(fp_line
			(start 0.7874 -0.4064)
			(end 0.7874 0.4064)
			(stroke
				(width 0.1524)
				(type default)
			)
			(layer "F.SilkS")
		)
		(fp_line
			(start -0.67945 0.3048)
			(end -0.67945 -0.305054)
			(stroke
				(width 0.1)
				(type default)
			)
			(layer "F.Fab")
		)
		(fp_line
			(start -0.12065 0.3048)
			(end -0.67945 0.3048)
			(stroke
				(width 0.1)
				(type default)
			)
			(layer "F.Fab")
		)
		(fp_line
			(start 0.120396 0.3048)
			(end 0.120396 0.2794)
			(stroke
				(width 0.1)
				(type default)
			)
			(layer "F.Fab")
		)
		(fp_line
			(start 0.67945 0.3048)
			(end 0.120396 0.3048)
			(stroke
				(width 0.1)
				(type default)
			)
			(layer "F.Fab")
		)
		(fp_line
			(start -0.12065 0.2794)
			(end -0.12065 0.3048)
			(stroke
				(width 0.1)
				(type default)
			)
			(layer "F.Fab")
		)
		(fp_line
			(start 0.120396 0.2794)
			(end -0.12065 0.2794)
			(stroke
				(width 0.1)
				(type default)
			)
			(layer "F.Fab")
		)
		(fp_line
			(start -0.12065 -0.2794)
			(end 0.12065 -0.2794)
			(stroke
				(width 0.1)
				(type default)
			)
			(layer "F.Fab")
		)
		(fp_line
			(start 0.12065 -0.2794)
			(end 0.12065 -0.3048)
			(stroke
				(width 0.1)
				(type default)
			)
			(layer "F.Fab")
		)
		(fp_line
			(start 0.12065 -0.3048)
			(end 0.67945 -0.3048)
			(stroke
				(width 0.1)
				(type default)
			)
			(layer "F.Fab")
		)
		(fp_line
			(start 0.67945 -0.3048)
			(end 0.67945 0.3048)
			(stroke
				(width 0.1)
				(type default)
			)
			(layer "F.Fab")
		)
		(fp_line
			(start -0.67945 -0.305054)
			(end -0.12065 -0.305054)
			(stroke
				(width 0.1)
				(type default)
			)
			(layer "F.Fab")
		)
		(fp_line
			(start -0.12065 -0.305054)
			(end -0.12065 -0.2794)
			(stroke
				(width 0.1)
				(type default)
			)
			(layer "F.Fab")
		)
		(pad "1" smd circle
			(at -0.40005 0 270)
			(size 0 0)
			(layers "F.Cu" "F.Mask" "F.Paste")
			(net "FM_P2E_EQA1")
		)
		(pad "2" smd circle
			(at 0.40005 0 270)
			(size 0 0)
			(layers "F.Cu" "F.Mask" "F.Paste")
			(net "GND")
		)
	)
	(footprint ""
		(layer "F.Cu")
		(at 306.420266 -430.240186 180)
		(property "Reference" "C19"
			(at 0 0 180)
			(layer "F.SilkS")
			(hide yes)
			(effects
				(font
					(size 1.27 1.27)
				)
			)
		)
		(property "Value" ""
			(at 0 0 180)
			(layer "F.Fab")
			(effects
				(font
					(size 1.27 1.27)
				)
			)
		)
		(duplicate_pad_numbers_are_jumpers no)
		(fp_line
			(start 0.7874 0.4064)
			(end -0.7874 0.4064)
			(stroke
				(width 0.1524)
				(type default)
			)
			(layer "F.SilkS")
		)
		(fp_line
			(start 0.7874 -0.4064)
			(end 0.7874 0.4064)
			(stroke
				(width 0.1524)
				(type default)
			)
			(layer "F.SilkS")
		)
		(fp_line
			(start -0.7874 0.4064)
			(end -0.7874 -0.4064)
			(stroke
				(width 0.1524)
				(type default)
			)
			(layer "F.SilkS")
		)
		(fp_line
			(start -0.7874 -0.4064)
			(end 0.7874 -0.4064)
			(stroke
				(width 0.1524)
				(type default)
			)
			(layer "F.SilkS")
		)
		(fp_line
			(start 0.67945 0.3048)
			(end 0.120396 0.3048)
			(stroke
				(width 0.1)
				(type default)
			)
			(layer "F.Fab")
		)
		(fp_line
			(start 0.67945 -0.3048)
			(end 0.67945 0.3048)
			(stroke
				(width 0.1)
				(type default)
			)
			(layer "F.Fab")
		)
		(fp_line
			(start 0.12065 -0.2794)
			(end 0.12065 -0.3048)
			(stroke
				(width 0.1)
				(type default)
			)
			(layer "F.Fab")
		)
		(fp_line
			(start 0.12065 -0.3048)
			(end 0.67945 -0.3048)
			(stroke
				(width 0.1)
				(type default)
			)
			(layer "F.Fab")
		)
		(fp_line
			(start 0.120396 0.3048)
			(end 0.120396 0.2794)
			(stroke
				(width 0.1)
				(type default)
			)
			(layer "F.Fab")
		)
		(fp_line
			(start 0.120396 0.2794)
			(end -0.12065 0.2794)
			(stroke
				(width 0.1)
				(type default)
			)
			(layer "F.Fab")
		)
		(fp_line
			(start -0.12065 0.3048)
			(end -0.67945 0.3048)
			(stroke
				(width 0.1)
				(type default)
			)
			(layer "F.Fab")
		)
		(fp_line
			(start -0.12065 0.2794)
			(end -0.12065 0.3048)
			(stroke
				(width 0.1)
				(type default)
			)
			(layer "F.Fab")
		)
		(fp_line
			(start -0.12065 -0.2794)
			(end 0.12065 -0.2794)
			(stroke
				(width 0.1)
				(type default)
			)
			(layer "F.Fab")
		)
		(fp_line
			(start -0.12065 -0.305054)
			(end -0.12065 -0.2794)
			(stroke
				(width 0.1)
				(type default)
			)
			(layer "F.Fab")
		)
		(fp_line
			(start -0.67945 0.3048)
			(end -0.67945 -0.305054)
			(stroke
				(width 0.1)
				(type default)
			)
			(layer "F.Fab")
		)
		(fp_line
			(start -0.67945 -0.305054)
			(end -0.12065 -0.305054)
			(stroke
				(width 0.1)
				(type default)
			)
			(layer "F.Fab")
		)
		(pad "1" smd circle
			(at -0.40005 0 180)
			(size 0 0)
			(layers "F.Cu" "F.Mask" "F.Paste")
			(net "PRSNT_CABLE_GPU_A2_ISO_N")
		)
		(pad "2" smd circle
			(at 0.40005 0 180)
			(size 0 0)
			(layers "F.Cu" "F.Mask" "F.Paste")
			(net "GND")
		)
	)
)
